(kicad_pcb
	(version 20260206)
	(generator "pcbnew")
	(generator_version "10.0")
	(general
		(thickness 1.6)
		(legacy_teardrops no)
	)
	(paper "A4")
	(title_block
		(title "timecard-production-celestica-r4006 — R4006-B0001-02_R01.brd")
		(comment 1 "Time Appliance Project (Time Card) / footprints 233-235 of 1113")
	)
	(layers
		(0 "F.Cu" signal "TOP")
		(4 "In1.Cu" signal "L02_GND1")
		(6 "In2.Cu" signal "L03_SIG1")
		(8 "In3.Cu" signal "L04_GND2")
		(10 "In4.Cu" signal "L05_VCC1")
		(12 "In5.Cu" signal "L06_VCC2")
		(14 "In6.Cu" signal "L07_GND3")
		(16 "In7.Cu" signal "L08_SIG2")
		(18 "In8.Cu" signal "L09_GND4")
		(2 "B.Cu" signal "BOTTOM")
		(9 "F.Adhes" user "F.Adhesive")
		(11 "B.Adhes" user "B.Adhesive")
		(13 "F.Paste" user "Package Geometry/Pastemask Top")
		(15 "B.Paste" user "Package Geometry/Pastemask Bottom")
		(5 "F.SilkS" user "Ref Des/Silkscreen Top")
		(7 "B.SilkS" user "Ref Des/Silkscreen Bottom")
		(1 "F.Mask" user "Board Geometry/Soldermask Top")
		(3 "B.Mask" user "Board Geometry/Soldermask Bottom")
		(17 "Dwgs.User" user "User.Drawings")
		(19 "Cmts.User" user "User.Comments")
		(21 "Eco1.User" user "User.Eco1")
		(23 "Eco2.User" user "User.Eco2")
		(25 "Edge.Cuts" user "Board Geometry/Outline")
		(27 "Margin" user)
		(31 "F.CrtYd" user "Package Geometry/Place Bound Top")
		(29 "B.CrtYd" user "Package Geometry/Place Bound Bottom")
		(35 "F.Fab" user "Ref Des/Assembly Top")
		(33 "B.Fab" user "Ref Des/Assembly Bottom")
	)
	(footprint ""
		(layer "F.Cu")
		(at 13.462 -52.578 -90)
		(property "Reference" "R121"
			(at 0.508 3.38963 90)
			(unlocked yes)
			(layer "F.SilkS")
			(effects
				(font
					(size 0.7874 0.5842)
					(thickness 0.1524)
				)
			)
		)
		(property "Value" "VAL*"
			(at 0.02032 2.13233 270)
			(unlocked yes)
			(layer "F.Fab")
			(hide yes)
			(effects
				(font
					(size 0.7874 0.5842)
					(thickness 0.1524)
				)
			)
		)
		(property "Tolerance" "TOL*"
			(at 0.044704 3.05435 270)
			(unlocked yes)
			(layer "Cmts.User")
			(hide yes)
			(effects
				(font
					(size 0.7874 0.5842)
					(thickness 0.1524)
				)
			)
		)
		(property "User Part Number" "PARTNUM*"
			(at 0.02032 4.024884 270)
			(unlocked yes)
			(layer "Cmts.User")
			(hide yes)
			(effects
				(font
					(size 0.7874 0.5842)
					(thickness 0.1524)
				)
			)
		)
		(property "Device Type" "RESISTOR-G155-11000-01,100OHM,A"
			(at 0.008382 1.210564 270)
			(unlocked yes)
			(layer "F.Fab")
			(hide yes)
			(effects
				(font
					(size 0.7874 0.5842)
					(thickness 0.1524)
				)
			)
		)
		(duplicate_pad_numbers_are_jumpers no)
		(fp_line
			(start -1.143 0.5588)
			(end 1.143 0.5588)
			(stroke
				(width 0.1)
				(type default)
			)
			(layer "F.SilkS")
		)
		(fp_line
			(start 1.143 0.5588)
			(end 1.143 -0.5588)
			(stroke
				(width 0.1)
				(type default)
			)
			(layer "F.SilkS")
		)
		(fp_line
			(start -1.143 -0.5588)
			(end -1.143 0.5588)
			(stroke
				(width 0.1)
				(type default)
			)
			(layer "F.SilkS")
		)
		(fp_line
			(start 1.143 -0.5588)
			(end -1.143 -0.5588)
			(stroke
				(width 0.1)
				(type default)
			)
			(layer "F.SilkS")
		)
		(fp_poly
			(pts
				(xy -1.143 0.5588) (xy 1.143 0.5588) (xy 1.143 -0.5588) (xy -1.143 -0.5588)
			)
			(stroke
				(width 0)
				(type default)
			)
			(fill no)
			(layer "F.CrtYd")
		)
		(fp_line
			(start -0.508 0.3048)
			(end 0.508 0.3048)
			(stroke
				(width 0.1)
				(type default)
			)
			(layer "F.Fab")
		)
		(fp_line
			(start 0.508 0.3048)
			(end 0.508 -0.3048)
			(stroke
				(width 0.1)
				(type default)
			)
			(layer "F.Fab")
		)
		(fp_line
			(start -0.508 -0.3048)
			(end -0.508 0.3048)
			(stroke
				(width 0.1)
				(type default)
			)
			(layer "F.Fab")
		)
		(fp_line
			(start 0.508 -0.3048)
			(end -0.508 -0.3048)
			(stroke
				(width 0.1)
				(type default)
			)
			(layer "F.Fab")
		)
		(pad "1" smd rect
			(at -0.5334 0 270)
			(size 0.7112 0.6096)
			(layers "F.Cu" "F.Mask" "F.Paste")
			(net "ANT2_OUT")
		)
		(pad "2" smd rect
			(at 0.5334 0 270)
			(size 0.7112 0.6096)
			(layers "F.Cu" "F.Mask" "F.Paste")
			(net "UNNAMED_12_74HCT2G125DPTSSOP8_9")
		)
		(zone
			(layer "F.Cu")
			(hatch none 0.5)
			(connect_pads
				(clearance 0)
			)
			(min_thickness 0.25)
			(keepout
				(tracks allowed)
				(vias not_allowed)
				(pads allowed)
				(copperpour not_allowed)
				(footprints allowed)
			)
			(placement
				(enabled no)
				(sheetname "")
			)
			(fill
				(thermal_gap 0.5)
				(thermal_bridge_width 0.5)
				(island_removal_mode 0)
			)
			(polygon
				(pts
					(xy 13.1572 -52.6542) (xy 13.1572 -52.5018) (xy 13.7668 -52.5018) (xy 13.7668 -52.6542)
				)
			)
		)
		(zone
			(layer "F.Cu")
			(hatch none 0.5)
			(connect_pads
				(clearance 0)
			)
			(min_thickness 0.25)
			(keepout
				(tracks not_allowed)
				(vias allowed)
				(pads allowed)
				(copperpour not_allowed)
				(footprints allowed)
			)
			(placement
				(enabled no)
				(sheetname "")
			)
			(fill
				(thermal_gap 0.5)
				(thermal_bridge_width 0.5)
				(island_removal_mode 0)
			)
			(polygon
				(pts
					(xy 13.1572 -52.6542) (xy 13.1572 -52.5018) (xy 13.7668 -52.5018) (xy 13.7668 -52.6542)
				)
			)
		)
	)
	(footprint ""
		(layer "F.Cu")
		(at 32.021018 -67.066922)
		(property "Reference" "MAC_PIN1"
			(at 0.127762 2.834132 0)
			(unlocked yes)
			(layer "F.SilkS")
			(effects
				(font
					(size 0.7874 0.5842)
					(thickness 0.1524)
				)
			)
		)
		(property "Value" ""
			(at 0 0 0)
			(layer "F.Fab")
			(effects
				(font
					(size 1.27 1.27)
				)
			)
		)
		(property "Device Type" "NUT-A200-00029-FB"
			(at 0 2.632964 0)
			(unlocked yes)
			(layer "F.Fab")
			(hide yes)
			(effects
				(font
					(size 0.7874 0.5842)
					(thickness 0.1524)
				)
			)
		)
		(property "User Part Number" "PARTNUM*"
			(at 0 3.826764 0)
			(unlocked yes)
			(layer "Cmts.User")
			(hide yes)
			(effects
				(font
					(size 0.7874 0.5842)
					(thickness 0.1524)
				)
			)
		)
		(duplicate_pad_numbers_are_jumpers no)
		(fp_circle
			(center 0 0)
			(end 1.524 0)
			(stroke
				(width 0.1)
				(type default)
			)
			(fill no)
			(layer "F.SilkS")
		)
		(fp_poly
			(pts
				(arc
					(start -1.260856 -0.1524)
					(mid -0.898049 -0.898049)
					(end -0.1524 -1.260856)
				)
				(arc
					(start -0.1524 -0.991616)
					(mid -0.709411 -0.709411)
					(end -0.991616 -0.1524)
				)
			)
			(stroke
				(width 0)
				(type default)
			)
			(fill yes)
			(layer "F.Paste")
		)
		(fp_poly
			(pts
				(arc
					(start -0.1524 1.260856)
					(mid -0.898049 0.898049)
					(end -1.260856 0.1524)
				)
				(arc
					(start -0.991616 0.1524)
					(mid -0.709411 0.709411)
					(end -0.1524 0.991616)
				)
			)
			(stroke
				(width 0)
				(type default)
			)
			(fill yes)
			(layer "F.Paste")
		)
		(fp_poly
			(pts
				(arc
					(start 0.1524 -1.260856)
					(mid 0.898049 -0.898049)
					(end 1.260856 -0.1524)
				)
				(arc
					(start 0.991616 -0.1524)
					(mid 0.709411 -0.709411)
					(end 0.1524 -0.991616)
				)
			)
			(stroke
				(width 0)
				(type default)
			)
			(fill yes)
			(layer "F.Paste")
		)
		(fp_poly
			(pts
				(arc
					(start 1.260856 0.1524)
					(mid 0.898049 0.898049)
					(end 0.1524 1.260856)
				)
				(arc
					(start 0.1524 0.991616)
					(mid 0.709411 0.709411)
					(end 0.991616 0.1524)
				)
			)
			(stroke
				(width 0)
				(type default)
			)
			(fill yes)
			(layer "F.Paste")
		)
		(fp_poly
			(pts
				(arc
					(start 6.35 0)
					(mid -6.35 0)
					(end 6.35 0)
				)
			)
			(stroke
				(width 0)
				(type default)
			)
			(fill no)
			(layer "B.CrtYd")
		)
		(fp_poly
			(pts
				(arc
					(start 1.778 0)
					(mid -1.778 0)
					(end 1.778 0)
				)
			)
			(stroke
				(width 0)
				(type default)
			)
			(fill no)
			(layer "F.CrtYd")
		)
		(fp_circle
			(center 0 0)
			(end 1.1684 0)
			(stroke
				(width 0.1)
				(type default)
			)
			(fill no)
			(layer "F.Fab")
		)
		(pad "1" thru_hole circle
			(at 0 0)
			(size 2.54 2.54)
			(drill 2.0066)
			(layers "*.Cu" "*.Mask")
			(remove_unused_layers no)
			(net "ANALOG_TUNING_IN")
			(thermal_gap 0.0254)
			(padstack
				(mode front_inner_back)
				(layer "Inner"
					(shape circle)
					(size 2.54 2.54)
					(clearance 0.0254)
				)
				(layer "B.Cu"
					(shape circle)
					(size 2.54 2.54)
				)
			)
		)
	)
	(footprint ""
		(layer "F.Cu")
		(at 145.8214 -97.9678)
		(property "Reference" "C7"
			(at 2.6416 -0.41783 0)
			(unlocked yes)
			(layer "F.SilkS")
			(effects
				(font
					(size 0.7874 0.5842)
					(thickness 0.1524)
				)
			)
		)
		(property "Value" "VAL*"
			(at 0.0762 2.067306 0)
			(unlocked yes)
			(layer "F.Fab")
			(hide yes)
			(effects
				(font
					(size 0.7874 0.5842)
					(thickness 0.1524)
				)
			)
		)
		(property "Device Type" "CAPACITOR-G105-0B104-EK,0.1UF,A"
			(at 0.0508 1.127506 0)
			(unlocked yes)
			(layer "F.Fab")
			(hide yes)
			(effects
				(font
					(size 0.7874 0.5842)
					(thickness 0.1524)
				)
			)
		)
		(property "User Part Number" "PARTNUM*"
			(at 0.1016 4.023106 0)
			(unlocked yes)
			(layer "Cmts.User")
			(hide yes)
			(effects
				(font
					(size 0.7874 0.5842)
					(thickness 0.1524)
				)
			)
		)
		(property "Tolerance" "TOL*"
			(at 0.0762 3.032506 0)
			(unlocked yes)
			(layer "Cmts.User")
			(hide yes)
			(effects
				(font
					(size 0.7874 0.5842)
					(thickness 0.1524)
				)
			)
		)
		(duplicate_pad_numbers_are_jumpers no)
		(fp_line
			(start -1.143 -0.5588)
			(end -1.143 0.5588)
			(stroke
				(width 0.1)
				(type default)
			)
			(layer "F.SilkS")
		)
		(fp_line
			(start -1.143 0.5588)
			(end 1.143 0.5588)
			(stroke
				(width 0.1)
				(type default)
			)
			(layer "F.SilkS")
		)
		(fp_line
			(start 1.143 -0.5588)
			(end -1.143 -0.5588)
			(stroke
				(width 0.1)
				(type default)
			)
			(layer "F.SilkS")
		)
		(fp_line
			(start 1.143 0.5588)
			(end 1.143 -0.5588)
			(stroke
				(width 0.1)
				(type default)
			)
			(layer "F.SilkS")
		)
		(fp_rect
			(start -1.143 0.5588)
			(end 1.143 -0.5588)
			(stroke
				(width 0)
				(type default)
			)
			(fill no)
			(layer "F.CrtYd")
		)
		(fp_line
			(start -0.508 -0.3048)
			(end -0.508 0.3048)
			(stroke
				(width 0.1)
				(type default)
			)
			(layer "F.Fab")
		)
		(fp_line
			(start -0.508 0.3048)
			(end 0.508 0.3048)
			(stroke
				(width 0.1)
				(type default)
			)
			(layer "F.Fab")
		)
		(fp_line
			(start 0.508 -0.3048)
			(end -0.508 -0.3048)
			(stroke
				(width 0.1)
				(type default)
			)
			(layer "F.Fab")
		)
		(fp_line
			(start 0.508 0.3048)
			(end 0.508 -0.3048)
			(stroke
				(width 0.1)
				(type default)
			)
			(layer "F.Fab")
		)
		(pad "1" smd rect
			(at -0.5334 0)
			(size 0.7112 0.6096)
			(layers "F.Cu" "F.Mask" "F.Paste")
			(net "XP12R0V_A_IMON")
		)
		(pad "2" smd rect
			(at 0.5334 0)
			(size 0.7112 0.6096)
			(layers "F.Cu" "F.Mask" "F.Paste")
			(net "SG")
		)
		(zone
			(layer "F.Cu")
			(hatch none 0.5)
			(connect_pads
				(clearance 0)
			)
			(min_thickness 0.25)
			(keepout
				(tracks allowed)
				(vias not_allowed)
				(pads allowed)
				(copperpour not_allowed)
				(footprints allowed)
			)
			(placement
				(enabled no)
				(sheetname "")
			)
			(fill
				(thermal_gap 0.5)
				(thermal_bridge_width 0.5)
				(island_removal_mode 0)
			)
			(polygon
				(pts
					(xy 145.7452 -97.663) (xy 145.8976 -97.663) (xy 145.8976 -98.2726) (xy 145.7452 -98.2726)
				)
			)
		)
	)
)
